# Jetson Orin Baseboard — KiCad custom design rules (.kicad_dru)
(version 1)

#---------------------- USB 2.0 ----------------------
(rule "(usb_2.0_inner"
	(layer inner)
	(condition "(A.NetClass == '85Ohm-diff_USB_2.0')")
	(constraint track_width (opt 0.16mm))
	(constraint diff_pair_gap  (opt 0.138mm))
#	(constraint diff_pair_uncoupled (max 2mm))
)
(rule "(usb_2.0_outer"
	(layer outer)
	(condition "(A.NetClass == '85Ohm-diff_USB_2.0')")
	(constraint track_width (opt 0.155mm))
	(constraint diff_pair_gap  (opt 0.144mm))
#	(constraint diff_pair_uncoupled (max 2mm))
)

#--------------------- HDMI/DP ----------------------
(rule "(hdmi_inner"
	(layer inner)
	(condition "(A.NetClass == '100Ohm-diff_HDMI')")
	(constraint track_width (opt 0.125mm))
	(constraint diff_pair_gap  (opt 0.225mm))
#	(constraint diff_pair_uncoupled (max 2mm))
)
(rule "(hdmi_outer"
	(layer outer)
	(condition "(A.NetClass == '100Ohm-diff_HDMI')")
	(constraint track_width (opt 0.125mm))
	(constraint diff_pair_gap  (opt 0.125mm))
#	(constraint diff_pair_uncoupled (max 2mm))
)

(rule "(hdmi_clearance"
	(condition "A.NetClass == '100Ohm-diff_HDMI' && !AB.isCoupledDiffPair() && A.Type == 'Track' && B.Type == 'Track'")
	(constraint clearance (min 0.2mm))
)

#--------------------- ETHERNET MDI ----------------------
(rule "(mdi_inner"
	(layer inner)
	(condition "(A.NetClass == '100Ohm-diff_MDI')")
	(constraint track_width (opt 0.125mm))
	(constraint diff_pair_gap  (opt 0.225mm))
#	(constraint diff_pair_uncoupled (max 2mm))
)
(rule "(mdi_outer"
	(layer outer)
	(condition "(A.NetClass == '100Ohm-diff_MDI')")
	(constraint track_width (opt 0.125mm))
	(constraint diff_pair_gap  (opt 0.222mm))
#	(constraint diff_pair_uncoupled (max 2mm))
)

(rule "(mdi_clearance"
	(condition "A.NetClass == '100Ohm-diff_MDI' && !AB.isCoupledDiffPair() && A.Type == 'Track' && B.Type == 'Track'")
	(constraint clearance (min 0.2mm))
)


#-------------------- D-PHY CSI ---------------------
(rule "(csi_inner"
	(layer inner)
	(condition "(A.NetClass == '85Ohm-diff_CSI')")
	(constraint track_width  (opt 0.16mm))
	(constraint diff_pair_gap  (opt 0.138mm))
#	(constraint diff_pair_uncoupled (max 2mm))
)
(rule "(csi_outer"
	(layer outer)
	(condition "(A.NetClass == '85Ohm-diff_CSI')")
	(constraint track_width (opt 0.155mm))
	(constraint diff_pair_gap  (opt 0.144mm) )
#	(constraint diff_pair_uncoupled (max 2mm))
)

(rule "(csi_clearance"
	(layer inner)
	(condition "A.NetClass == '85Ohm-diff_CSI' && !AB.isCoupledDiffPair() && A.Type == 'Track' && B.Type == 'Track'")
	(constraint clearance (min 0.2mm))
)

#---------------------- USB SS ----------------------
(rule "(usb_ss_inner"
	(layer inner)
	(condition "(A.NetClass == '85Ohm-diff_USB_SS')")
	(constraint track_width (opt 0.16mm))
	(constraint diff_pair_gap  (opt 0.138mm))
#	(constraint diff_pair_uncoupled (max 2mm))
)
(rule "(usb_ss_outer"
	(layer outer)
	(condition "(A.NetClass == '85Ohm-diff_USB_SS')")
	(constraint track_width (opt 0.155mm))
	(constraint diff_pair_gap  (opt 0.144mm))
#	(constraint diff_pair_uncoupled (max 2mm))
)

(rule "(usb_ss_clearance"
	(condition "A.NetClass == '85Ohm-diff_USB_SS' && !AB.isCoupledDiffPair() && A.Type == 'Track' && B.Type == 'Track'")
	(constraint clearance (min 0.2mm))
)


#----------------------- PCIe -----------------------
(rule "(pcie_inner"
	(layer inner)
	(condition "(A.NetClass == '85Ohm-diff_PCIE')")
	(constraint track_width (opt 0.16mm))
	(constraint diff_pair_gap  (opt 0.138mm))
#	(constraint diff_pair_uncoupled (max 2mm))
)
(rule "(pcie_outer"
	(layer outer)
	(condition "(A.NetClass == '85Ohm-diff_PCIE')")
	(constraint track_width (opt 0.155mm))
	(constraint diff_pair_gap  (opt 0.144mm))
#	(constraint diff_pair_uncoupled (max 2mm))
)

(rule "(pcie_clearance"
	(condition "A.NetClass == '85Ohm-diff_PCIE' && !AB.isCoupledDiffPair() && A.Type == 'Track' && B.Type == 'Track'")
#	(constraint clearance (min 0.8mm))
)

#---------------------------------------------

(rule "clearance1"
	(constraint clearance (min 0.125mm))
	(condition "A.insideCourtyard('U10') || B.insideCourtyard('U10')")
)

(rule "clearance3"
	(constraint clearance (min 0.125mm))
	(constraint hole_clearance (min 0.25mm))
	(condition "A.NetName == 'GND' && !(A.Type == 'Zone' && B.Type == 'Zone')")
)
(rule clearance_PoE
	(condition "A.NetClass == 'Default' && B.NetClass == 'PoE'")
	(constraint clearance (min 0.5mm))
)

(rule "allow_overlap" 
    (condition "A.intersectsArea('allow_overlap')")
    (constraint courtyard_clearance (min -1mm))
    (constraint silk_clearance (min -1mm))
)

(rule "clearance 3V3_SW"
	(constraint clearance (min 0.5mm))
	(condition "A.Type == 'Zone' &&  A.NetName == '/Supply/3V3_SW' && B.Pad_Type == 'Through-hole'")
)
